FILE_TYPE = CONNECTIVITY;
{Allegro Design Entry HDL 16.6-p007 (v16-6-112F) 10/10/2012}
"PAGE_NUMBER" = 125;
0"NC";
1"GND\g";
2"GND\g";
3"GND\g";
4"P3V3_STBY\g";
5"P3V3_STBY\g";
6"P3V3_STBY\g";
7"GND\g";
8"GND\g";
9"P3V3_STBY\g";
10"P3V3_STBY\g";
11"GND\g";
12"P3V3_STBY\g";
13"P3V3_STBY\g";
14"P3V3_STBY\g";
15"P3V3_STBY\g";
16"FM_USB_P0_EN_BOOT_BIOS_STRAP_N";
17"SPI_PCH_IO2";
18"PU_PCH_TLS_ENABLE_STRAP";
19"FM_UV_ADR_TRIGGER_EN";
20"FM_FLASH_DESC_OVERRIDE";
21"RMII_BMC_PCH_SPRNGVLLE_RXER";
22"SPI_PCH_MOSI";
23"PU_ADR_TIMER_HOLD_OFF_N";
24"RMII_PCH_SPRNGVLLE_ARB_OUT";
25"SPI_PCH_IO3";
%"RES"
"2","(1750,3050)","0","mstr_discrete","I11";
;
PART_NUMBER"G21796-026"
LOCATION"R2R11"
TOLERANCE"1%"
MATERIAL"EMPTY"
WATTAGE"1/16W"
PACK_TYPE"0402"
VALUE"1.00K"
BOM_COST"SB"
CDS_SEC"1"
$SEC"1"
CDS_LOCATION"R2R11"
ROOM"SB"
CDS_LIB"mstr_discrete";
"A"
$PN"1"17;
"B"
$PN"2"1;
%"GND"
"1","(1750,2800)","0","mstr_symbols","I14";
;
SIZE"1B"
BOM_COST"SB"
ROOM"SB"
CDS_LIB"mstr_symbols"
VOLTAGE"0.0V"
BODY_TYPE"PLUMBING"
HDL_POWER"GND";
"A\NAC"1;
%"GND"
"1","(1850,1225)","0","mstr_symbols","I16";
;
BOM_COST"SB"
ROOM"SB"
VOLTAGE"0.0V"
CDS_LIB"mstr_symbols"
SIZE"1B"
BODY_TYPE"PLUMBING"
HDL_POWER"GND";
"A\NAC"2;
%"RES"
"2","(-950,3150)","0","mstr_discrete","I21";
;
CDS_SEC"1"
LOCATION"R8E6"
VALUE"1.00K"
TOLERANCE"1%"
WATTAGE"1/16W"
MATERIAL"EMPTY"
PACK_TYPE"0402"
PART_NUMBER"G21796-026"
SEC_TYPE"0402"
SEC"1"
BOM_COST"SB"
ROOM"SB"
CDS_LOCATION"R8E6"
CDS_LIB"mstr_discrete";
"A"
$PN"1"4;
"B"
$PN"2"22;
%"RES"
"2","(-950,2750)","0","mstr_discrete","I24";
;
WATTAGE"1/16W"
TOLERANCE"1%"
LOCATION"R8E4"
VALUE"1.00K"
MATERIAL"EMPTY"
PACK_TYPE"0402"
PART_NUMBER"G21796-026"
$SEC"1"
CDS_SEC"1"
BOM_COST"SB"
ROOM"SB"
CDS_LOCATION"R8E4"
CDS_LIB"mstr_discrete";
"A"
$PN"1"22;
"B"
$PN"2"3;
%"GND"
"1","(-950,2500)","0","mstr_symbols","I25";
;
ROOM"SB"
BOM_COST"SB"
VOLTAGE"0.0V"
SIZE"1B"
CDS_LIB"mstr_symbols"
BODY_TYPE"PLUMBING"
HDL_POWER"GND";
"A\NAC"3;
%"RES"
"2","(-3225,2525)","0","mstr_discrete","I40";
;
VALUE"1.00K"
WATTAGE"1/16W"
TOLERANCE"1%"
LOCATION"R8C18"
PACK_TYPE"0402"
PART_NUMBER"G21796-026"
MATERIAL"CHIP"
CDS_SEC"1"
BOM_COST"SB"
$SEC"1"
CDS_LOCATION"R8C18"
ROOM"SB"
CDS_LIB"mstr_discrete";
"A"
$PN"1"5;
"B"
$PN"2"18;
%"RES"
"2","(-3225,2200)","0","mstr_discrete","I41";
;
CDS_SEC"1"
PART_NUMBER"G21796-026"
TOLERANCE"1%"
VALUE"1.00K"
MATERIAL"EMPTY"
LOCATION"R8C17"
WATTAGE"1/16W"
PACK_TYPE"0402"
ROOM"SB"
SEC"1"
BOM_COST"SB"
SEC_TYPE"0402"
CDS_LOCATION"R8C17"
CDS_LIB"mstr_discrete";
"A"
$PN"1"18;
"B"
$PN"2"8;
%"P3V3_STBY"
"1","(-950,3375)","0","mstr_symbols","I48";
;
VOLTAGE"3.3V"
CDS_LIB"mstr_symbols"
SIZE"1B"
BODY_TYPE"PLUMBING"
HDL_POWER"P3V3_STBY";
"G\NAC"4;
%"P3V3_STBY"
"1","(-3225,2750)","0","mstr_symbols","I49";
;
SIZE"1B"
CDS_LIB"mstr_symbols"
VOLTAGE"3.3V"
BODY_TYPE"PLUMBING"
HDL_POWER"P3V3_STBY";
"G\NAC"5;
%"RES"
"2","(-925,4450)","0","mstr_discrete","I50";
;
MATERIAL"EMPTY"
WATTAGE"1/16W"
TOLERANCE"1%"
VALUE"1.00K"
LOCATION"R8D5"
PACK_TYPE"0402"
PART_NUMBER"G21796-026"
CDS_LIB"mstr_discrete"
CDS_LOCATION"R8D5"
BOM_COST"SB"
CDS_SEC"1"
$SEC"1"
ROOM"SB";
"A"
$PN"1"23;
"B"
$PN"2"7;
%"P3V3_STBY"
"1","(-925,5100)","0","mstr_symbols","I51";
;
SIZE"1B"
CDS_LIB"mstr_symbols"
VOLTAGE"3.3V"
BODY_TYPE"PLUMBING"
HDL_POWER"P3V3_STBY";
"G\NAC"6;
%"GND"
"1","(-925,4200)","0","mstr_symbols","I54";
;
SIZE"1B"
ROOM"SB"
BOM_COST"SB"
CDS_LIB"mstr_symbols"
VOLTAGE"0.0V"
BODY_TYPE"PLUMBING"
HDL_POWER"GND";
"A\NAC"7;
%"GND"
"1","(-3225,2000)","0","mstr_symbols","I6";
;
BOM_COST"SB"
ROOM"SB"
VOLTAGE"0.0V"
CDS_LIB"mstr_symbols"
SIZE"1B"
BODY_TYPE"PLUMBING"
HDL_POWER"GND";
"A\NAC"8;
%"RES"
"2","(-3275,4975)","0","mstr_discrete","I60";
;
MATERIAL"EMPTY"
PACK_TYPE"0402"
LOCATION"R7D13"
VALUE"8.2K"
TOLERANCE"1%"
WATTAGE"1/16W"
PART_NUMBER"G21796-345"
ROOM"SB"
$SEC"1"
CDS_SEC"1"
BOM_COST"SB"
CDS_LOCATION"R7D13"
CDS_LIB"mstr_discrete";
"A"
$PN"1"9;
"B"
$PN"2"21;
%"P3V3_STBY"
"1","(-3275,5200)","0","mstr_symbols","I61";
;
CDS_LIB"mstr_symbols"
SIZE"1B"
VOLTAGE"3.3V"
BODY_TYPE"PLUMBING"
HDL_POWER"P3V3_STBY";
"G\NAC"9;
%"P3V3_STBY"
"1","(-5050,3975)","0","mstr_symbols","I66";
;
CDS_LIB"mstr_symbols"
SIZE"1B"
VOLTAGE"3.3V"
BODY_TYPE"PLUMBING"
HDL_POWER"P3V3_STBY";
"G\NAC"10;
%"GND"
"1","(-5050,3175)","0","mstr_symbols","I69";
;
SIZE"1B"
ROOM"SB"
BOM_COST"SB"
CDS_LIB"mstr_symbols"
VOLTAGE"0.0V"
BODY_TYPE"PLUMBING"
HDL_POWER"GND";
"A\NAC"11;
%"RES"
"2","(400,4600)","0","mstr_discrete","I72";
;
CDS_SEC"1"
LOCATION"R3N2"
VALUE"4.75K"
TOLERANCE"1%"
PACK_TYPE"0402"
WATTAGE"1/16W"
PART_NUMBER"G21796-072"
MATERIAL"EMPTY"
SEC_TYPE"0402"
SEC"1"
CDS_LOCATION"R3N2"
BOM_COST"SB"
ROOM"BMC_MISC"
CDS_LIB"mstr_discrete";
"A"
$PN"1"12;
"B"
$PN"2"20;
%"P3V3_STBY"
"1","(400,4900)","0","mstr_symbols","I74";
;
SIZE"1B"
CDS_LIB"mstr_symbols"
VOLTAGE"3.3V"
BODY_TYPE"PLUMBING"
HDL_POWER"P3V3_STBY";
"G\NAC"12;
%"P3V3_STBY"
"1","(-3350,1600)","0","mstr_symbols","I75";
;
SIZE"1B"
CDS_LIB"mstr_symbols"
VOLTAGE"3.3V"
BODY_TYPE"PLUMBING"
HDL_POWER"P3V3_STBY";
"G\NAC"13;
%"RES"
"2","(1850,1875)","0","mstr_discrete","I78";
;
CDS_SEC"1"
PACK_TYPE"0402"
TOLERANCE"1%"
LOCATION"R3N17"
MATERIAL"EMPTY"
PART_NUMBER"G21796-026"
WATTAGE"1/16W"
VALUE"1.00K"
CDS_LIB"mstr_discrete"
CDS_LOCATION"R3N17"
BOM_COST"SB"
SEC_TYPE"0402"
SEC"1"
ROOM"SB";
"A"
$PN"1"14;
"B"
$PN"2"25;
%"P3V3_STBY"
"1","(1850,2125)","0","mstr_symbols","I79";
;
CDS_LIB"mstr_symbols"
SIZE"1B"
VOLTAGE"3.3V"
BODY_TYPE"PLUMBING"
HDL_POWER"P3V3_STBY";
"G\NAC"14;
%"RES"
"2","(-925,1525)","0","mstr_discrete","I83";
;
CDS_SEC"1"
TOLERANCE"1%"
MATERIAL"EMPTY"
PART_NUMBER"G21796-026"
PACK_TYPE"0402"
LOCATION"R2N14"
VALUE"1.00K"
WATTAGE"1/16W"
SEC_TYPE"0402"
ROOM"SB"
SEC"1"
BOM_COST"SB"
CDS_LOCATION"R2N14"
CDS_LIB"mstr_discrete";
"A"
$PN"1"15;
"B"
$PN"2"16;
%"P3V3_STBY"
"1","(-925,1750)","0","mstr_symbols","I84";
;
SIZE"1B"
VOLTAGE"3.3V"
CDS_LIB"mstr_symbols"
BODY_TYPE"PLUMBING"
HDL_POWER"P3V3_STBY";
"G\NAC"15;
%"RES"
"2","(-5050,3775)","0","mstr_discrete","I85";
;
VALUE"10.0K"
LOCATION"R8D16"
TOLERANCE"1%"
WATTAGE"1/16W"
MATERIAL"CHIP"
PART_NUMBER"G21796-016"
PACK_TYPE"0402"
CDS_SEC"1"
$SEC"1"
BOM_COST"SB"
ROOM"SB_HEADERS"
CDS_LIB"mstr_discrete"
CDS_LOCATION"R8D16";
"A"
$PN"1"10;
"B"
$PN"2"24;
%"RES"
"2","(-5050,3375)","0","mstr_discrete","I86";
;
LOCATION"R7D1"
PACK_TYPE"0402"
TOLERANCE"1%"
VALUE"1.00K"
WATTAGE"1/16W"
MATERIAL"EMPTY"
PART_NUMBER"G21796-026"
CDS_LOCATION"R7D1"
CDS_LIB"mstr_discrete"
BOM_COST"SB"
CDS_SEC"1"
$SEC"1"
ROOM"SB";
"A"
$PN"1"24;
"B"
$PN"2"11;
%"RES"
"2","(-925,4925)","0","mstr_discrete","I87";
;
CDS_SEC"1"
PACK_TYPE"0402"
TOLERANCE"1%"
MATERIAL"EMPTY"
WATTAGE"1/16W"
LOCATION"R8D13"
PART_NUMBER"G21796-016"
VALUE"10.0K"
CDS_LOCATION"R8D13"
ROOM"DB1200ZL"
SEC"1"
SEC_TYPE"0402"
BOM_COST"SYS_CLOCK"
CDS_LIB"mstr_discrete";
"A"
$PN"1"6;
"B"
$PN"2"23;
%"RES"
"2","(-3350,1375)","2","mstr_discrete","I88";
;
CDS_SEC"1"
VALUE"4.75K"
LOCATION"R2U30"
TOLERANCE"1%"
PART_NUMBER"G21796-072"
MATERIAL"EMPTY"
WATTAGE"1/16W"
PACK_TYPE"0402"
CDS_LOCATION"R2U30"
SEC_TYPE"0402"
BOM_COST"SYS_CLOCK"
SEC"1"
ROOM"DB1200ZL"
CDS_LIB"mstr_discrete";
"A"
$PN"1"13;
"B"
$PN"2"19;
%"RES"
"2","(1850,1475)","0","mstr_discrete","I89";
;
CDS_SEC"1"
PACK_TYPE"0402"
WATTAGE"1/16W"
TOLERANCE"1%"
MATERIAL"EMPTY"
PART_NUMBER"G21796-026"
LOCATION"R2T1"
VALUE"1.00K"
CDS_LIB"mstr_discrete"
BOM_COST"SB"
SEC_TYPE"0402"
SEC"1"
ROOM"SB"
CDS_LOCATION"R2T1";
"A"
$PN"1"25;
"B"
$PN"2"2;
END.
